# T6G (Grand Teton) — schematic netlist excerpt (pin names and nets, part order shuffled) for the footprints in the layout excerpt that follows; sources: Cadence DE-HDL packaged netlist, KiCad conversion of 04192023_DAF0TMB3IC0_F0TG_MB_C_brd_V02_OCP.brd

PD109  SCHOTTKY_AC  B340A-13-F IC  pkg D2010XF  page 140 : A = GND ; C = P3V3_OCP_V3_2_R
PR368  Q_RES  8.87K 1% EMPTY  pkg 0402LF  page 223 : A = PVDDIO_P1_LSET4 ; B = GND

(kicad_pcb
	(version 20260206)
	(generator "pcbnew")
	(generator_version "10.0")
	(general
		(thickness 1.6)
		(legacy_teardrops no)
	)
	(paper "A4")
	(title_block
		(title "04192023_DAF0TMB3IC0_F0TG_MB_C_brd_V02_OCP.brd")
		(comment 1 "Grand Teton / footprints 1045-1046 of 8354")
	)
	(layers
		(0 "F.Cu" signal "TOP")
		(4 "In1.Cu" signal "GND")
		(6 "In2.Cu" signal "IN1")
		(8 "In3.Cu" signal "GND1")
		(10 "In4.Cu" signal "IN2")
		(12 "In5.Cu" signal "GND2")
		(14 "In6.Cu" signal "IN3")
		(16 "In7.Cu" signal "GND3")
		(18 "In8.Cu" signal "VCC")
		(20 "In9.Cu" signal "VCC1")
		(22 "In10.Cu" signal "GND4")
		(24 "In11.Cu" signal "IN4")
		(26 "In12.Cu" signal "GND5")
		(28 "In13.Cu" signal "IN5")
		(30 "In14.Cu" signal "GND6")
		(32 "In15.Cu" signal "IN6")
		(34 "In16.Cu" signal "GND7")
		(2 "B.Cu" signal "BOTTOM")
		(9 "F.Adhes" user "F.Adhesive")
		(11 "B.Adhes" user "B.Adhesive")
		(13 "F.Paste" user "Package Geometry/Pastemask Top")
		(15 "B.Paste" user "Package Geometry/Pastemask Bottom")
		(5 "F.SilkS" user "Ref Des/Silkscreen Top")
		(7 "B.SilkS" user "Ref Des/Silkscreen Bottom")
		(1 "F.Mask" user "Board Geometry/Soldermask Top")
		(3 "B.Mask" user "Board Geometry/Soldermask Bottom")
		(17 "Dwgs.User" user "User.Drawings")
		(19 "Cmts.User" user "User.Comments")
		(21 "Eco1.User" user "User.Eco1")
		(23 "Eco2.User" user "User.Eco2")
		(25 "Edge.Cuts" user "Board Geometry/Outline")
		(27 "Margin" user)
		(31 "F.CrtYd" user "Package Geometry/Place Bound Top")
		(29 "B.CrtYd" user "Package Geometry/Place Bound Bottom")
		(35 "F.Fab" user "Ref Des/Assembly Top")
		(33 "B.Fab" user "Ref Des/Assembly Bottom")
	)
	(footprint ""
		(layer "F.Cu")
		(at 27.29611 -351.932748)
		(property "Reference" "PR368"
			(at 0 0 0)
			(layer "F.SilkS")
			(hide yes)
			(effects
				(font
					(size 1.27 1.27)
				)
			)
		)
		(property "Value" ""
			(at 0 0 0)
			(layer "F.Fab")
			(effects
				(font
					(size 1.27 1.27)
				)
			)
		)
		(duplicate_pad_numbers_are_jumpers no)
		(fp_line
			(start -0.7874 -0.4064)
			(end 0.7874 -0.4064)
			(stroke
				(width 0.1524)
				(type default)
			)
			(layer "F.SilkS")
		)
		(fp_line
			(start -0.7874 0.4064)
			(end -0.7874 -0.4064)
			(stroke
				(width 0.1524)
				(type default)
			)
			(layer "F.SilkS")
		)
		(fp_line
			(start 0.7874 -0.4064)
			(end 0.7874 0.4064)
			(stroke
				(width 0.1524)
				(type default)
			)
			(layer "F.SilkS")
		)
		(fp_line
			(start 0.7874 0.4064)
			(end -0.7874 0.4064)
			(stroke
				(width 0.1524)
				(type default)
			)
			(layer "F.SilkS")
		)
		(fp_line
			(start -0.67945 -0.305054)
			(end -0.12065 -0.305054)
			(stroke
				(width 0.1)
				(type default)
			)
			(layer "F.Fab")
		)
		(fp_line
			(start -0.67945 0.3048)
			(end -0.67945 -0.305054)
			(stroke
				(width 0.1)
				(type default)
			)
			(layer "F.Fab")
		)
		(fp_line
			(start -0.12065 -0.305054)
			(end -0.12065 -0.2794)
			(stroke
				(width 0.1)
				(type default)
			)
			(layer "F.Fab")
		)
		(fp_line
			(start -0.12065 -0.2794)
			(end 0.12065 -0.2794)
			(stroke
				(width 0.1)
				(type default)
			)
			(layer "F.Fab")
		)
		(fp_line
			(start -0.12065 0.2794)
			(end -0.12065 0.3048)
			(stroke
				(width 0.1)
				(type default)
			)
			(layer "F.Fab")
		)
		(fp_line
			(start -0.12065 0.3048)
			(end -0.67945 0.3048)
			(stroke
				(width 0.1)
				(type default)
			)
			(layer "F.Fab")
		)
		(fp_line
			(start 0.120396 0.2794)
			(end -0.12065 0.2794)
			(stroke
				(width 0.1)
				(type default)
			)
			(layer "F.Fab")
		)
		(fp_line
			(start 0.120396 0.3048)
			(end 0.120396 0.2794)
			(stroke
				(width 0.1)
				(type default)
			)
			(layer "F.Fab")
		)
		(fp_line
			(start 0.12065 -0.3048)
			(end 0.67945 -0.3048)
			(stroke
				(width 0.1)
				(type default)
			)
			(layer "F.Fab")
		)
		(fp_line
			(start 0.12065 -0.2794)
			(end 0.12065 -0.3048)
			(stroke
				(width 0.1)
				(type default)
			)
			(layer "F.Fab")
		)
		(fp_line
			(start 0.67945 -0.3048)
			(end 0.67945 0.3048)
			(stroke
				(width 0.1)
				(type default)
			)
			(layer "F.Fab")
		)
		(fp_line
			(start 0.67945 0.3048)
			(end 0.120396 0.3048)
			(stroke
				(width 0.1)
				(type default)
			)
			(layer "F.Fab")
		)
		(pad "1" smd circle
			(at -0.40005 0)
			(size 0 0)
			(layers "F.Cu" "F.Mask" "F.Paste")
			(net "PVDDIO_P1_LSET4")
		)
		(pad "2" smd circle
			(at 0.40005 0)
			(size 0 0)
			(layers "F.Cu" "F.Mask" "F.Paste")
			(net "GND")
		)
	)
	(footprint ""
		(layer "F.Cu")
		(at 97.902522 -67.038982 -90)
		(property "Reference" "PD109"
			(at 4.125722 -2.54254 90)
			(unlocked yes)
			(layer "F.SilkS")
			(effects
				(font
					(size 0.7874 0.5842)
					(thickness 0.1524)
				)
				(justify left)
			)
		)
		(property "Value" ""
			(at 0 0 270)
			(layer "F.Fab")
			(effects
				(font
					(size 1.27 1.27)
				)
			)
		)
		(duplicate_pad_numbers_are_jumpers no)
		(fp_line
			(start -3.400044 1.459992)
			(end -3.400044 -1.459992)
			(stroke
				(width 0.1524)
				(type default)
			)
			(layer "F.SilkS")
		)
		(fp_line
			(start 4.107942 1.459992)
			(end -3.400044 1.459992)
			(stroke
				(width 0.1524)
				(type default)
			)
			(layer "F.SilkS")
		)
		(fp_line
			(start -3.400044 -1.459992)
			(end 4.107942 -1.459992)
			(stroke
				(width 0.1524)
				(type default)
			)
			(layer "F.SilkS")
		)
		(fp_line
			(start 4.107942 -1.459992)
			(end 4.107942 1.459992)
			(stroke
				(width 0.1524)
				(type default)
			)
			(layer "F.SilkS")
		)
		(fp_rect
			(start 4.107942 1.459992)
			(end 3.308096 -1.459992)
			(stroke
				(width 0)
				(type default)
			)
			(fill yes)
			(layer "F.SilkS")
		)
		(fp_line
			(start -2.29997 1.459992)
			(end -2.29997 -1.459992)
			(stroke
				(width 0.1)
				(type default)
			)
			(layer "F.Fab")
		)
		(fp_line
			(start 2.29997 1.459992)
			(end -2.29997 1.459992)
			(stroke
				(width 0.1)
				(type default)
			)
			(layer "F.Fab")
		)
		(fp_line
			(start -2.29997 -1.459992)
			(end 2.29997 -1.459992)
			(stroke
				(width 0.1)
				(type default)
			)
			(layer "F.Fab")
		)
		(fp_line
			(start 2.29997 -1.459992)
			(end 2.29997 1.459992)
			(stroke
				(width 0.1)
				(type default)
			)
			(layer "F.Fab")
		)
		(fp_text user "-"
			(at 5.4102 0.29845 90)
			(unlocked yes)
			(layer "F.SilkS")
			(effects
				(font
					(size 1.905 1.4224)
					(thickness 0.1524)
				)
				(justify left)
			)
		)
		(fp_text user "+"
			(at -5.329174 -1.367536 270)
			(unlocked yes)
			(layer "F.SilkS")
			(effects
				(font
					(size 1.905 1.4224)
					(thickness 0.1524)
				)
				(justify left)
			)
		)
		(fp_text user "-"
			(at 5.4102 0.29845 90)
			(unlocked yes)
			(layer "F.Fab")
			(effects
				(font
					(size 1.905 1.4224)
					(thickness 0.1524)
				)
				(justify left)
			)
		)
		(fp_text user "+"
			(at -4.7752 -0.12065 270)
			(unlocked yes)
			(layer "F.Fab")
			(effects
				(font
					(size 1.905 1.4224)
					(thickness 0.1524)
				)
				(justify left)
			)
		)
		(pad "A" smd rect
			(at -1.999996 0)
			(size 1.7018 2.5146)
			(layers "F.Cu" "F.Mask" "F.Paste")
			(net "GND")
		)
		(pad "C" smd rect
			(at 1.999996 0)
			(size 1.7018 2.5146)
			(layers "F.Cu" "F.Mask" "F.Paste")
			(net "P3V3_OCP_V3_2_R")
		)
	)
)
